# S9S_MB_2U (Grand Teton) — schematic netlist excerpt (pin names and nets, part order shuffled) for the footprints in the layout excerpt that follows; sources: Cadence DE-HDL packaged netlist, KiCad conversion of 03242023_DA0F0TMBIJ0_F0T_Motherboard_J_brd_V01_OCP.brd

J22  SCONN288_ADR50017P087CC  SCONN288_ADR50017-P087CC IO  pkg DDR288S_1-1VXB  page 103
  VIN_BULK0  = P12V_S3_AUX_CPU1_NVDIMM
  RFU0  = TP_CHC_CPU1_DIMM2_FRU_0
  VIN_MGMT  = P3V3_AUX
  HSCL  = I3C_SPD_DDRABCD_CPU1_LVC1_SCL_5
  HSDA  = I3C_SPD_DDRABCD_CPU1_LVC1_SDA
  VSS0  = GND
  DQ0_A  = M_C_CPU1_SA_DQ<0>
  VSS1  = GND
  DQ1_A  = M_C_CPU1_SA_DQ<1>
  VSS2  = GND
  DQS0_A_T  = M_C_CPU1_SA_DQS_DP<0>
  DQS0_A_C  = M_C_CPU1_SA_DQS_DN<0>
  VSS3  = GND
  DQ4_A  = M_C_CPU1_SA_DQ<4>
  VSS4  = GND
  DQ5_A  = M_C_CPU1_SA_DQ<5>
  VSS5  = GND
  DQ8_A  = M_C_CPU1_SA_DQ<8>
  VSS6  = GND
  DQ9_A  = M_C_CPU1_SA_DQ<9>
  VSS7  = GND
  DQS1_A_T  = M_C_CPU1_SA_DQS_DP<1>
  DQS1_A_C  = M_C_CPU1_SA_DQS_DN<1>
  VSS8  = GND
  DQ12_A  = M_C_CPU1_SA_DQ<12>
  VSS9  = GND
  DQ13_A  = M_C_CPU1_SA_DQ<13>
  VSS10  = GND
  DQ16_A  = M_C_CPU1_SA_DQ<16>
  VSS11  = GND
  DQ17_A  = M_C_CPU1_SA_DQ<17>
  VSS12  = GND
  DQS2_A_T  = M_C_CPU1_SA_DQS_DP<2>
  DQS2_A_C  = M_C_CPU1_SA_DQS_DN<2>
  VSS13  = GND
  DQ20_A  = M_C_CPU1_SA_DQ<20>
  VSS14  = GND
  DQ21_A  = M_C_CPU1_SA_DQ<21>
  VSS15  = GND
  DQ24_A  = M_C_CPU1_SA_DQ<24>
  VSS16  = GND
  DQ25_A  = M_C_CPU1_SA_DQ<25>
  VSS17  = GND
  DQS3_A_T  = M_C_CPU1_SA_DQS_DP<3>
  DQS3_A_C  = M_C_CPU1_SA_DQS_DN<3>
  VSS18  = GND
  DQ28_A  = M_C_CPU1_SA_DQ<28>
  VSS19  = GND
  DQ29_A  = M_C_CPU1_SA_DQ<29>
  VSS20  = GND
  CB0_A  = M_C_CPU1_SA_CB<0>
  VSS21  = GND
  CB1_A  = M_C_CPU1_SA_CB<1>
  VSS22  = GND
  DQS4_A_T  = M_C_CPU1_SA_DQS_DP<4>
  DQS4_A_C  = M_C_CPU1_SA_DQS_DN<4>
  VSS23  = GND
  CB4_A  = M_C_CPU1_SA_CB<4>
  VSS24  = GND
  CB5_A  = M_C_CPU1_SA_CB<5>
  VSS25  = GND
  ALERT_N  = M_C_CPU1_ALERT_N
  VSS26  = GND
  CS0_A_N  = M_C_CPU1_SA_CS_N<2>
  VSS27  = GND
  CA0_A  = M_C_CPU1_SA_CA<0>
  VSS28  = GND
  CA2_A  = M_C_CPU1_SA_CA<2>
  VSS29  = GND
  CA4_A  = M_C_CPU1_SA_CA<4>
  VSS30  = GND
  CA6_A  = M_C_CPU1_SA_CA<6>
  VSS31  = GND
  PAR_A  = M_C_CPU1_SA_PAR
  VSS32  = GND
  CA0_B  = M_C_CPU1_SB_CA<0>
  VSS33  = GND
  CA2_B  = M_C_CPU1_SB_CA<2>
  VSS34  = GND
  CA4_B  = M_C_CPU1_SB_CA<4>
  VSS35  = GND
  CA6_B  = M_C_CPU1_SB_CA<6>
  VSS36  = GND
  CS0_B_N  = M_C_CPU1_SB_CS_N<2>
  VSS37  = GND
  \lbd||rsp_a_n\  = M_C_CPU1_SA_RSP<1>
  \lbs||rsp_b_n\  = M_C_CPU1_SB_RSP<1>
  VSS38  = GND
  CB4_B  = M_C_CPU1_SB_CB<4>
  VSS39  = GND
  CB5_B  = M_C_CPU1_SB_CB<5>
  VSS40  = GND
  \dqs9_b_t||tdqs9_b_t||dbi4_b_n\  = M_C_CPU1_SB_DQS_DP<9>
  \dqs9_b_c||tdqs9_b_c\  = M_C_CPU1_SB_DQS_DN<9>
  VSS41  = GND
  CB0_B  = M_C_CPU1_SB_CB<0>
  VSS42  = GND
  CB1_B  = M_C_CPU1_SB_CB<1>
  VSS43  = GND
  DQ0_B  = M_C_CPU1_SB_DQ<0>
  VSS44  = GND
  DQ1_B  = M_C_CPU1_SB_DQ<1>
  VSS45  = GND
  DQS0_B_T  = M_C_CPU1_SB_DQS_DP<0>
  DQS0_B_C  = M_C_CPU1_SB_DQS_DN<0>
  VSS46  = GND
  DQ4_B  = M_C_CPU1_SB_DQ<4>
  VSS47  = GND
  DQ5_B  = M_C_CPU1_SB_DQ<5>
  VSS48  = GND
  DQ8_B  = M_C_CPU1_SB_DQ<8>
  VSS49  = GND
  DQ9_B  = M_C_CPU1_SB_DQ<9>
  VSS50  = GND
  DQS1_B_T  = M_C_CPU1_SB_DQS_DP<1>
  DQS1_B_C  = M_C_CPU1_SB_DQS_DN<1>
  VSS51  = GND
  DQ12_B  = M_C_CPU1_SB_DQ<12>
  VSS52  = GND
  DQ13_B  = M_C_CPU1_SB_DQ<13>
  VSS53  = GND
  DQ16_B  = M_C_CPU1_SB_DQ<16>
  VSS54  = GND
  DQ17_B  = M_C_CPU1_SB_DQ<17>
  VSS55  = GND
  DQS2_B_T  = M_C_CPU1_SB_DQS_DP<2>
  DQS2_B_C  = M_C_CPU1_SB_DQS_DN<2>
  VSS56  = GND
  DQ20_B  = M_C_CPU1_SB_DQ<20>
  VSS57  = GND
  DQ21_B  = M_C_CPU1_SB_DQ<21>
  VSS58  = GND
  DQ24_B  = M_C_CPU1_SB_DQ<24>
  VSS59  = GND
  DQ25_B  = M_C_CPU1_SB_DQ<25>
  VSS60  = GND
  DQS3_B_T  = M_C_CPU1_SB_DQS_DP<3>
  DQS3_B_C  = M_C_CPU1_SB_DQS_DN<3>
  VSS61  = GND
  DQ28_B  = M_C_CPU1_SB_DQ<28>
  VSS62  = GND
  DQ29_B  = M_C_CPU1_SB_DQ<29>
  VSS63  = GND
  RFU1  = TP_CHC_CPU1_DIMM2_FRU_1
  VIN_BULK1  = P12V_S3_AUX_CPU1_NVDIMM
  VIN_BULK2  = P12V_S3_AUX_CPU1_NVDIMM
  \pwr_good||fail_n\  = PWRGD_CHC_CPU1_DIMM2
  HSA  = PD_CHC_CPU1_DIMM2_SAA
  RFU2  = TP_CHC_CPU1_DIMM2_FRU_2
  RFU3  = TP_CHC_CPU1_DIMM2_FRU_3
  VSS64  = GND
  DQ2_A  = M_C_CPU1_SA_DQ<2>
  VSS65  = GND
  DQ3_A  = M_C_CPU1_SA_DQ<3>
  VSS66  = GND
  \dqs5_a_c||tdqs5_a_c||dqs5_a_t||tdqs5_a_t\  = M_C_CPU1_SA_DQS_DN<5>
  \dqs5_a_t||tdqs5_a_t\  = M_C_CPU1_SA_DQS_DP<5>
  VSS67  = GND
  DQ6_A  = M_C_CPU1_SA_DQ<6>
  VSS68  = GND
  DQ7_A  = M_C_CPU1_SA_DQ<7>
  VSS69  = GND
  DQ10_A  = M_C_CPU1_SA_DQ<10>
  VSS70  = GND
  DQ11_A  = M_C_CPU1_SA_DQ<11>
  VSS71  = GND
  \dqs6_a_c||tdqs6_a_c||dqs6_a_t||tdqs6_a_t\  = M_C_CPU1_SA_DQS_DN<6>
  \dqs6_a_t||tdqs6_a_t\  = M_C_CPU1_SA_DQS_DP<6>
  VSS72  = GND
  DQ14_A  = M_C_CPU1_SA_DQ<14>
  VSS73  = GND
  DQ15_A  = M_C_CPU1_SA_DQ<15>
  VSS74  = GND
  DQ18_A  = M_C_CPU1_SA_DQ<18>
  VSS75  = GND
  DQ19_A  = M_C_CPU1_SA_DQ<19>
  VSS76  = GND
  \dqs7_a_c||tdqs7_a_c\  = M_C_CPU1_SA_DQS_DN<7>
  \dqs7_a_t||tdqs7_a_t\  = M_C_CPU1_SA_DQS_DP<7>
  VSS77  = GND
  DQ22_A  = M_C_CPU1_SA_DQ<22>
  VSS78  = GND
  DQ23_A  = M_C_CPU1_SA_DQ<23>
  VSS79  = GND
  DQ26_A  = M_C_CPU1_SA_DQ<26>
  VSS80  = GND
  DQ27_A  = M_C_CPU1_SA_DQ<27>
  VSS81  = GND
  \dqs8_a_c||tdqs8_a_c\  = M_C_CPU1_SA_DQS_DN<8>
  \dqs8_a_t||tdqs8_a_t\  = M_C_CPU1_SA_DQS_DP<8>
  VSS82  = GND
  DQ30_A  = M_C_CPU1_SA_DQ<30>
  VSS83  = GND
  DQ31_A  = M_C_CPU1_SA_DQ<31>
  VSS84  = GND
  CB2_A  = M_C_CPU1_SA_CB<2>
  VSS85  = GND
  CB3_A  = M_C_CPU1_SA_CB<3>
  VSS86  = GND
  \dqs9_a_c||tdqs9_a_c\  = M_C_CPU1_SA_DQS_DN<9>
  \dqs9_a_t||tdqs9_a_t\  = M_C_CPU1_SA_DQS_DP<9>
  VSS87  = GND
  CB6_A  = M_C_CPU1_SA_CB<6>
  VSS88  = GND
  CB7_A  = M_C_CPU1_SA_CB<7>
  VSS89  = GND
  RESET_N  = RST_M_CD_CPU1_FPGA_N
  VSS90  = GND
  CS1_A_N  = M_C_CPU1_SA_CS_N<3>
  VSS91  = GND
  CA1_A  = M_C_CPU1_SA_CA<1>
  VSS92  = GND
  CA3_A  = M_C_CPU1_SA_CA<3>
  VSS93  = GND
  CA5_A  = M_C_CPU1_SA_CA<5>
  VSS94  = GND
  CK_T  = M_C_CPU1_CLK_DP<1>
  CK_C  = M_C_CPU1_CLK_DN<1>
  VSS95  = GND
  RFU4  = TP_CHC_CPU1_DIMM2_FRU_4
  CA1_B  = M_C_CPU1_SB_CA<1>
  VSS96  = GND
  CA3_B  = M_C_CPU1_SB_CA<3>
  VSS97  = GND
  CA5_B  = M_C_CPU1_SB_CA<5>
  VSS98  = GND
  PAR_B  = M_C_CPU1_SB_PAR
  VSS99  = GND
  CS1_B_N  = M_C_CPU1_SB_CS_N<3>
  VSS100  = GND
  RFU5  = TP_CHC_CPU1_DIMM2_FRU_5
  RFU6  = TP_CHC_CPU1_DIMM2_FRU_6
  VSS101  = GND
  CB6_B  = M_C_CPU1_SB_CB<6>
  VSS102  = GND
  CB7_B  = M_C_CPU1_SB_CB<7>
  VSS103  = GND
  DQS4_B_C  = M_C_CPU1_SB_DQS_DN<4>
  DQS4_B_T  = M_C_CPU1_SB_DQS_DP<4>
  VSS104  = GND
  CB2_B  = M_C_CPU1_SB_CB<2>
  VSS105  = GND
  CB3_B  = M_C_CPU1_SB_CB<3>
  VSS106  = GND
  DQ2_B  = M_C_CPU1_SB_DQ<2>
  VSS107  = GND
  DQ3_B  = M_C_CPU1_SB_DQ<3>
  VSS108  = GND
  \dqs5_b_c||tdqs5_b_c\  = M_C_CPU1_SB_DQS_DN<5>
  \dqs5_b_t||tdqs5_b_t\  = M_C_CPU1_SB_DQS_DP<5>
  VSS109  = GND
  DQ6_B  = M_C_CPU1_SB_DQ<6>
  VSS110  = GND
  DQ7_B  = M_C_CPU1_SB_DQ<7>
  VSS111  = GND
  DQ10_B  = M_C_CPU1_SB_DQ<10>
  VSS112  = GND
  DQ11_B  = M_C_CPU1_SB_DQ<11>
  VSS113  = GND
  \dqs6_b_c||tdqs6_b_c\  = M_C_CPU1_SB_DQS_DN<6>
  \dqs6_b_t||tdqs6_b_t\  = M_C_CPU1_SB_DQS_DP<6>
  VSS114  = GND
  DQ14_B  = M_C_CPU1_SB_DQ<14>
  VSS115  = GND
  DQ15_B  = M_C_CPU1_SB_DQ<15>
  VSS116  = GND
  DQ18_B  = M_C_CPU1_SB_DQ<18>
  VSS117  = GND
  DQ19_B  = M_C_CPU1_SB_DQ<19>
  VSS118  = GND
  \dqs7_b_c||tdqs7_b_c\  = M_C_CPU1_SB_DQS_DN<7>
  \dqs7_b_t||tdqs7_b_t\  = M_C_CPU1_SB_DQS_DP<7>
  VSS119  = GND
  DQ22_B  = M_C_CPU1_SB_DQ<22>
  VSS120  = GND
  DQ23_B  = M_C_CPU1_SB_DQ<23>
  VSS121  = GND
  DQ26_B  = M_C_CPU1_SB_DQ<26>
  VSS122  = GND
  DQ27_B  = M_C_CPU1_SB_DQ<27>
  VSS123  = GND
  \dqs8_b_c||tdqs8_b_c\  = M_C_CPU1_SB_DQS_DN<8>
  \dqs8_b_t||tdqs8_b_t\  = M_C_CPU1_SB_DQS_DP<8>
  VSS124  = GND
  DQ30_B  = M_C_CPU1_SB_DQ<30>
  VSS125  = GND
  DQ31_B  = M_C_CPU1_SB_DQ<31>
  VSS126  = GND
  G1  = GND
  G2  = GND
  G3  = GND

(kicad_pcb
	(version 20260206)
	(generator "pcbnew")
	(generator_version "10.0")
	(general
		(thickness 1.6)
		(legacy_teardrops no)
	)
	(paper "A4")
	(title_block
		(title "03242023_DA0F0TMBIJ0_F0T_Motherboard_J_brd_V01_OCP.brd")
		(comment 1 "Grand Teton / footprint 501 of 6105 (J22), pads 1-45 of 291")
	)
	(layers
		(0 "F.Cu" signal "TOP")
		(4 "In1.Cu" signal "GND")
		(6 "In2.Cu" signal "IN1")
		(8 "In3.Cu" signal "GND1")
		(10 "In4.Cu" signal "IN2")
		(12 "In5.Cu" signal "GND2")
		(14 "In6.Cu" signal "IN3")
		(16 "In7.Cu" signal "GND3")
		(18 "In8.Cu" signal "VCC")
		(20 "In9.Cu" signal "VCC1")
		(22 "In10.Cu" signal "GND4")
		(24 "In11.Cu" signal "IN4")
		(26 "In12.Cu" signal "GND5")
		(28 "In13.Cu" signal "IN5")
		(30 "In14.Cu" signal "GND6")
		(32 "In15.Cu" signal "IN6")
		(34 "In16.Cu" signal "GND7")
		(2 "B.Cu" signal "BOTTOM")
		(9 "F.Adhes" user "F.Adhesive")
		(11 "B.Adhes" user "B.Adhesive")
		(13 "F.Paste" user "Package Geometry/Pastemask Top")
		(15 "B.Paste" user "Package Geometry/Pastemask Bottom")
		(5 "F.SilkS" user "Ref Des/Silkscreen Top")
		(7 "B.SilkS" user "Ref Des/Silkscreen Bottom")
		(1 "F.Mask" user "Board Geometry/Soldermask Top")
		(3 "B.Mask" user "Board Geometry/Soldermask Bottom")
		(17 "Dwgs.User" user "User.Drawings")
		(19 "Cmts.User" user "User.Comments")
		(21 "Eco1.User" user "User.Eco1")
		(23 "Eco2.User" user "User.Eco2")
		(25 "Edge.Cuts" user "Board Geometry/Outline")
		(27 "Margin" user)
		(31 "F.CrtYd" user "Package Geometry/Place Bound Top")
		(29 "B.CrtYd" user "Package Geometry/Place Bound Bottom")
		(35 "F.Fab" user "Ref Des/Assembly Top")
		(33 "B.Fab" user "Ref Des/Assembly Bottom")
	)
	(footprint ""
		(layer "F.Cu")
		(at 32.82188 -258.091686)
		(property "Reference" "J22"
			(at -1.420622 -81.912714 0)
			(unlocked yes)
			(layer "F.SilkS")
			(effects
				(font
					(size 0.7874 0.5842)
					(thickness 0.1524)
				)
				(justify left)
			)
		)
		(property "Value" ""
			(at 0 0 0)
			(layer "F.Fab")
			(effects
				(font
					(size 1.27 1.27)
				)
			)
		)
		(duplicate_pad_numbers_are_jumpers no)
		(pad "1" smd rect
			(at -2.050034 -63.324994 270)
			(size 0.519938 1.4986)
			(layers "F.Cu" "F.Mask" "F.Paste")
			(net "P12V_S3_AUX_CPU1_NVDIMM")
		)
		(pad "2" smd rect
			(at -2.050034 -62.47511 270)
			(size 0.519938 1.4986)
			(layers "F.Cu" "F.Mask" "F.Paste")
			(net "TP_CHC_CPU1_DIMM2_FRU_0")
		)
		(pad "3" smd rect
			(at -2.050034 -61.624972 270)
			(size 0.519938 1.4986)
			(layers "F.Cu" "F.Mask" "F.Paste")
			(net "P3V3_AUX")
		)
		(pad "4" smd rect
			(at -2.050034 -60.775088 270)
			(size 0.519938 1.4986)
			(layers "F.Cu" "F.Mask" "F.Paste")
			(net "I3C_SPD_DDRABCD_CPU1_LVC1_SCL_5")
		)
		(pad "5" smd rect
			(at -2.050034 -59.92495 270)
			(size 0.519938 1.4986)
			(layers "F.Cu" "F.Mask" "F.Paste")
			(net "I3C_SPD_DDRABCD_CPU1_LVC1_SDA")
		)
		(pad "6" smd rect
			(at -2.050034 -59.075066 270)
			(size 0.519938 1.4986)
			(layers "F.Cu" "F.Mask" "F.Paste")
			(net "GND")
		)
		(pad "7" smd rect
			(at -2.050034 -58.224928 270)
			(size 0.519938 1.4986)
			(layers "F.Cu" "F.Mask" "F.Paste")
			(net "M_C_CPU1_SA_DQ<0>")
		)
		(pad "8" smd rect
			(at -2.050034 -57.375044 270)
			(size 0.519938 1.4986)
			(layers "F.Cu" "F.Mask" "F.Paste")
			(net "GND")
		)
		(pad "9" smd rect
			(at -2.050034 -56.524906 270)
			(size 0.519938 1.4986)
			(layers "F.Cu" "F.Mask" "F.Paste")
			(net "M_C_CPU1_SA_DQ<1>")
		)
		(pad "10" smd rect
			(at -2.050034 -55.675022 270)
			(size 0.519938 1.4986)
			(layers "F.Cu" "F.Mask" "F.Paste")
			(net "GND")
		)
		(pad "11" smd rect
			(at -2.050034 -54.824884 270)
			(size 0.519938 1.4986)
			(layers "F.Cu" "F.Mask" "F.Paste")
			(net "M_C_CPU1_SA_DQS_DP<0>")
		)
		(pad "12" smd rect
			(at -2.050034 -53.975 270)
			(size 0.519938 1.4986)
			(layers "F.Cu" "F.Mask" "F.Paste")
			(net "M_C_CPU1_SA_DQS_DN<0>")
		)
		(pad "13" smd rect
			(at -2.050034 -53.125116 270)
			(size 0.519938 1.4986)
			(layers "F.Cu" "F.Mask" "F.Paste")
			(net "GND")
		)
		(pad "14" smd rect
			(at -2.050034 -52.274978 270)
			(size 0.519938 1.4986)
			(layers "F.Cu" "F.Mask" "F.Paste")
			(net "M_C_CPU1_SA_DQ<4>")
		)
		(pad "15" smd rect
			(at -2.050034 -51.425094 270)
			(size 0.519938 1.4986)
			(layers "F.Cu" "F.Mask" "F.Paste")
			(net "GND")
		)
		(pad "16" smd rect
			(at -2.050034 -50.574956 270)
			(size 0.519938 1.4986)
			(layers "F.Cu" "F.Mask" "F.Paste")
			(net "M_C_CPU1_SA_DQ<5>")
		)
		(pad "17" smd rect
			(at -2.050034 -49.725072 270)
			(size 0.519938 1.4986)
			(layers "F.Cu" "F.Mask" "F.Paste")
			(net "GND")
		)
		(pad "18" smd rect
			(at -2.050034 -48.874934 270)
			(size 0.519938 1.4986)
			(layers "F.Cu" "F.Mask" "F.Paste")
			(net "M_C_CPU1_SA_DQ<8>")
		)
		(pad "19" smd rect
			(at -2.050034 -48.02505 270)
			(size 0.519938 1.4986)
			(layers "F.Cu" "F.Mask" "F.Paste")
			(net "GND")
		)
		(pad "20" smd rect
			(at -2.050034 -47.174912 270)
			(size 0.519938 1.4986)
			(layers "F.Cu" "F.Mask" "F.Paste")
			(net "M_C_CPU1_SA_DQ<9>")
		)
		(pad "21" smd rect
			(at -2.050034 -46.325028 270)
			(size 0.519938 1.4986)
			(layers "F.Cu" "F.Mask" "F.Paste")
			(net "GND")
		)
		(pad "22" smd rect
			(at -2.050034 -45.47489 270)
			(size 0.519938 1.4986)
			(layers "F.Cu" "F.Mask" "F.Paste")
			(net "M_C_CPU1_SA_DQS_DP<1>")
		)
		(pad "23" smd rect
			(at -2.050034 -44.625006 270)
			(size 0.519938 1.4986)
			(layers "F.Cu" "F.Mask" "F.Paste")
			(net "M_C_CPU1_SA_DQS_DN<1>")
		)
		(pad "24" smd rect
			(at -2.050034 -43.775122 270)
			(size 0.519938 1.4986)
			(layers "F.Cu" "F.Mask" "F.Paste")
			(net "GND")
		)
		(pad "25" smd rect
			(at -2.050034 -42.924984 270)
			(size 0.519938 1.4986)
			(layers "F.Cu" "F.Mask" "F.Paste")
			(net "M_C_CPU1_SA_DQ<12>")
		)
		(pad "26" smd rect
			(at -2.050034 -42.0751 270)
			(size 0.519938 1.4986)
			(layers "F.Cu" "F.Mask" "F.Paste")
			(net "GND")
		)
		(pad "27" smd rect
			(at -2.050034 -41.224962 270)
			(size 0.519938 1.4986)
			(layers "F.Cu" "F.Mask" "F.Paste")
			(net "M_C_CPU1_SA_DQ<13>")
		)
		(pad "28" smd rect
			(at -2.050034 -40.375078 270)
			(size 0.519938 1.4986)
			(layers "F.Cu" "F.Mask" "F.Paste")
			(net "GND")
		)
		(pad "29" smd rect
			(at -2.050034 -39.52494 270)
			(size 0.519938 1.4986)
			(layers "F.Cu" "F.Mask" "F.Paste")
			(net "M_C_CPU1_SA_DQ<16>")
		)
		(pad "30" smd rect
			(at -2.050034 -38.675056 270)
			(size 0.519938 1.4986)
			(layers "F.Cu" "F.Mask" "F.Paste")
			(net "GND")
		)
		(pad "31" smd rect
			(at -2.050034 -37.824918 270)
			(size 0.519938 1.4986)
			(layers "F.Cu" "F.Mask" "F.Paste")
			(net "M_C_CPU1_SA_DQ<17>")
		)
		(pad "32" smd rect
			(at -2.050034 -36.975034 270)
			(size 0.519938 1.4986)
			(layers "F.Cu" "F.Mask" "F.Paste")
			(net "GND")
		)
		(pad "33" smd rect
			(at -2.050034 -36.124896 270)
			(size 0.519938 1.4986)
			(layers "F.Cu" "F.Mask" "F.Paste")
			(net "M_C_CPU1_SA_DQS_DP<2>")
		)
		(pad "34" smd rect
			(at -2.050034 -35.275012 270)
			(size 0.519938 1.4986)
			(layers "F.Cu" "F.Mask" "F.Paste")
			(net "M_C_CPU1_SA_DQS_DN<2>")
		)
		(pad "35" smd rect
			(at -2.050034 -34.425128 270)
			(size 0.519938 1.4986)
			(layers "F.Cu" "F.Mask" "F.Paste")
			(net "GND")
		)
		(pad "36" smd rect
			(at -2.050034 -33.57499 270)
			(size 0.519938 1.4986)
			(layers "F.Cu" "F.Mask" "F.Paste")
			(net "M_C_CPU1_SA_DQ<20>")
		)
		(pad "37" smd rect
			(at -2.050034 -32.725106 270)
			(size 0.519938 1.4986)
			(layers "F.Cu" "F.Mask" "F.Paste")
			(net "GND")
		)
		(pad "38" smd rect
			(at -2.050034 -31.874968 270)
			(size 0.519938 1.4986)
			(layers "F.Cu" "F.Mask" "F.Paste")
			(net "M_C_CPU1_SA_DQ<21>")
		)
		(pad "39" smd rect
			(at -2.050034 -31.025084 270)
			(size 0.519938 1.4986)
			(layers "F.Cu" "F.Mask" "F.Paste")
			(net "GND")
		)
		(pad "40" smd rect
			(at -2.050034 -30.174946 270)
			(size 0.519938 1.4986)
			(layers "F.Cu" "F.Mask" "F.Paste")
			(net "M_C_CPU1_SA_DQ<24>")
		)
		(pad "41" smd rect
			(at -2.050034 -29.325062 270)
			(size 0.519938 1.4986)
			(layers "F.Cu" "F.Mask" "F.Paste")
			(net "GND")
		)
		(pad "42" smd rect
			(at -2.050034 -28.474924 270)
			(size 0.519938 1.4986)
			(layers "F.Cu" "F.Mask" "F.Paste")
			(net "M_C_CPU1_SA_DQ<25>")
		)
		(pad "43" smd rect
			(at -2.050034 -27.62504 270)
			(size 0.519938 1.4986)
			(layers "F.Cu" "F.Mask" "F.Paste")
			(net "GND")
		)
		(pad "44" smd rect
			(at -2.050034 -26.774902 270)
			(size 0.519938 1.4986)
			(layers "F.Cu" "F.Mask" "F.Paste")
			(net "M_C_CPU1_SA_DQS_DP<3>")
		)
		(pad "45" smd rect
			(at -2.050034 -25.925018 270)
			(size 0.519938 1.4986)
			(layers "F.Cu" "F.Mask" "F.Paste")
			(net "M_C_CPU1_SA_DQS_DN<3>")
		)
	)
)
